(kicad_pcb
	(version 20260206)
	(generator "pcbnew")
	(generator_version "10.0")
	(general
		(thickness 1.6)
		(legacy_teardrops no)
	)
	(paper "A4")
	(title_block
		(title "03242023_DA0F0TMBIJ0_F0T_Motherboard_J_brd_V01_OCP.brd")
		(comment 1 "Grand Teton / footprints 3751-3753 of 6105")
	)
	(layers
		(0 "F.Cu" signal "TOP")
		(4 "In1.Cu" signal "GND")
		(6 "In2.Cu" signal "IN1")
		(8 "In3.Cu" signal "GND1")
		(10 "In4.Cu" signal "IN2")
		(12 "In5.Cu" signal "GND2")
		(14 "In6.Cu" signal "IN3")
		(16 "In7.Cu" signal "GND3")
		(18 "In8.Cu" signal "VCC")
		(20 "In9.Cu" signal "VCC1")
		(22 "In10.Cu" signal "GND4")
		(24 "In11.Cu" signal "IN4")
		(26 "In12.Cu" signal "GND5")
		(28 "In13.Cu" signal "IN5")
		(30 "In14.Cu" signal "GND6")
		(32 "In15.Cu" signal "IN6")
		(34 "In16.Cu" signal "GND7")
		(2 "B.Cu" signal "BOTTOM")
		(9 "F.Adhes" user "F.Adhesive")
		(11 "B.Adhes" user "B.Adhesive")
		(13 "F.Paste" user "Package Geometry/Pastemask Top")
		(15 "B.Paste" user "Package Geometry/Pastemask Bottom")
		(5 "F.SilkS" user "Ref Des/Silkscreen Top")
		(7 "B.SilkS" user "Ref Des/Silkscreen Bottom")
		(1 "F.Mask" user "Board Geometry/Soldermask Top")
		(3 "B.Mask" user "Board Geometry/Soldermask Bottom")
		(17 "Dwgs.User" user "User.Drawings")
		(19 "Cmts.User" user "User.Comments")
		(21 "Eco1.User" user "User.Eco1")
		(23 "Eco2.User" user "User.Eco2")
		(25 "Edge.Cuts" user "Board Geometry/Outline")
		(27 "Margin" user)
		(31 "F.CrtYd" user "Package Geometry/Place Bound Top")
		(29 "B.CrtYd" user "Package Geometry/Place Bound Bottom")
		(35 "F.Fab" user "Ref Des/Assembly Top")
		(33 "B.Fab" user "Ref Des/Assembly Bottom")
	)
	(footprint ""
		(layer "F.Cu")
		(at 14.064996 -99.136454 -90)
		(property "Reference" "U268"
			(at -3.321558 -3.514598 0)
			(unlocked yes)
			(layer "F.SilkS")
			(effects
				(font
					(size 0.7874 0.5842)
					(thickness 0.1524)
				)
				(justify left)
			)
		)
		(property "Value" ""
			(at 0 0 270)
			(layer "F.Fab")
			(effects
				(font
					(size 1.27 1.27)
				)
			)
		)
		(duplicate_pad_numbers_are_jumpers no)
		(fp_line
			(start -0.508 2.921)
			(end -0.508 3.683)
			(stroke
				(width 0.1524)
				(type default)
			)
			(layer "F.SilkS")
		)
		(fp_line
			(start -2.500122 2.500122)
			(end -2.500122 1.778)
			(stroke
				(width 0.1524)
				(type default)
			)
			(layer "F.SilkS")
		)
		(fp_line
			(start -1.778 2.500122)
			(end -2.500122 2.500122)
			(stroke
				(width 0.1524)
				(type default)
			)
			(layer "F.SilkS")
		)
		(fp_line
			(start 2.500122 2.500122)
			(end 1.778 2.500122)
			(stroke
				(width 0.1524)
				(type default)
			)
			(layer "F.SilkS")
		)
		(fp_line
			(start 2.500122 1.778)
			(end 2.500122 2.500122)
			(stroke
				(width 0.1524)
				(type default)
			)
			(layer "F.SilkS")
		)
		(fp_line
			(start 2.921 1.524)
			(end 3.302 1.524)
			(stroke
				(width 0.1524)
				(type default)
			)
			(layer "F.SilkS")
		)
		(fp_line
			(start -2.921 0.508)
			(end -3.302 0.508)
			(stroke
				(width 0.1524)
				(type default)
			)
			(layer "F.SilkS")
		)
		(fp_line
			(start 2.921 -1.016)
			(end 3.683 -1.016)
			(stroke
				(width 0.1524)
				(type default)
			)
			(layer "F.SilkS")
		)
		(fp_line
			(start -2.500122 -1.778)
			(end -2.500122 -2.500122)
			(stroke
				(width 0.1524)
				(type default)
			)
			(layer "F.SilkS")
		)
		(fp_line
			(start -2.500122 -2.500122)
			(end -1.778 -2.500122)
			(stroke
				(width 0.1524)
				(type default)
			)
			(layer "F.SilkS")
		)
		(fp_line
			(start 1.778 -2.500122)
			(end 2.500122 -2.500122)
			(stroke
				(width 0.1524)
				(type default)
			)
			(layer "F.SilkS")
		)
		(fp_line
			(start 2.500122 -2.500122)
			(end 2.500122 -1.778)
			(stroke
				(width 0.1524)
				(type default)
			)
			(layer "F.SilkS")
		)
		(fp_line
			(start 0 -2.921)
			(end 0 -3.302)
			(stroke
				(width 0.1524)
				(type default)
			)
			(layer "F.SilkS")
		)
		(fp_poly
			(pts
				(xy -2.65938 -1.724152) (xy -3.578352 -2.030222) (xy -2.965704 -2.64287)
			)
			(stroke
				(width 0)
				(type default)
			)
			(fill yes)
			(layer "F.SilkS")
		)
		(fp_line
			(start -0.508 2.921)
			(end -0.508 3.683)
			(stroke
				(width 0.1)
				(type default)
			)
			(layer "F.Fab")
		)
		(fp_line
			(start -2.500122 2.500122)
			(end -2.500122 -2.500122)
			(stroke
				(width 0.1)
				(type default)
			)
			(layer "F.Fab")
		)
		(fp_line
			(start 2.500122 2.500122)
			(end -2.500122 2.500122)
			(stroke
				(width 0.1)
				(type default)
			)
			(layer "F.Fab")
		)
		(fp_line
			(start 2.921 1.524)
			(end 3.302 1.524)
			(stroke
				(width 0.1)
				(type default)
			)
			(layer "F.Fab")
		)
		(fp_line
			(start -2.921 0.508)
			(end -3.302 0.508)
			(stroke
				(width 0.1)
				(type default)
			)
			(layer "F.Fab")
		)
		(fp_line
			(start 2.921 -1.016)
			(end 3.683 -1.016)
			(stroke
				(width 0.1)
				(type default)
			)
			(layer "F.Fab")
		)
		(fp_line
			(start -2.500122 -2.500122)
			(end 2.500122 -2.500122)
			(stroke
				(width 0.1)
				(type default)
			)
			(layer "F.Fab")
		)
		(fp_line
			(start 2.500122 -2.500122)
			(end 2.500122 2.500122)
			(stroke
				(width 0.1)
				(type default)
			)
			(layer "F.Fab")
		)
		(fp_line
			(start 0 -2.921)
			(end 0 -3.302)
			(stroke
				(width 0.1)
				(type default)
			)
			(layer "F.Fab")
		)
		(fp_poly
			(pts
				(xy -3.7592 -1.933194) (xy -2.892806 -1.500124) (xy -3.7592 -1.0668)
			)
			(stroke
				(width 0)
				(type default)
			)
			(fill yes)
			(layer "F.Fab")
		)
		(fp_text user "15"
			(at 4.098036 4.054856 0)
			(unlocked yes)
			(layer "F.SilkS")
			(effects
				(font
					(size 0.635 0.4064)
					(thickness 0.1524)
				)
			)
		)
		(fp_text user "14"
			(at 1.484376 3.513836 0)
			(unlocked yes)
			(layer "F.SilkS")
			(effects
				(font
					(size 0.635 0.4064)
					(thickness 0.1524)
				)
			)
		)
		(fp_text user "8"
			(at -2.064004 2.993136 0)
			(unlocked yes)
			(layer "F.SilkS")
			(effects
				(font
					(size 0.635 0.4064)
					(thickness 0.1524)
				)
			)
		)
		(fp_text user "7"
			(at -3.147568 1.8034 0)
			(unlocked yes)
			(layer "F.SilkS")
			(effects
				(font
					(size 0.635 0.4064)
					(thickness 0.1524)
				)
			)
		)
		(fp_text user "28"
			(at -1.304544 -3.471164 0)
			(unlocked yes)
			(layer "F.SilkS")
			(effects
				(font
					(size 0.635 0.4064)
					(thickness 0.1524)
				)
			)
		)
		(fp_text user "21"
			(at 4.557776 -3.974084 0)
			(unlocked yes)
			(layer "F.SilkS")
			(effects
				(font
					(size 0.635 0.4064)
					(thickness 0.1524)
				)
			)
		)
		(fp_text user "22"
			(at 3.315716 -4.591304 0)
			(unlocked yes)
			(layer "F.SilkS")
			(effects
				(font
					(size 0.635 0.4064)
					(thickness 0.1524)
				)
			)
		)
		(fp_text user "8"
			(at -1.8796 3.253232 270)
			(unlocked yes)
			(layer "F.Fab")
			(effects
				(font
					(size 0.635 0.4064)
					(thickness 0.1524)
				)
			)
		)
		(fp_text user "14"
			(at 2.1336 3.253232 270)
			(unlocked yes)
			(layer "F.Fab")
			(effects
				(font
					(size 0.635 0.4064)
					(thickness 0.1524)
				)
			)
		)
		(fp_text user "15"
			(at 3.253232 2.2352 0)
			(unlocked yes)
			(layer "F.Fab")
			(effects
				(font
					(size 0.635 0.4064)
					(thickness 0.1524)
				)
			)
		)
		(fp_text user "7"
			(at -3.147568 1.8034 0)
			(unlocked yes)
			(layer "F.Fab")
			(effects
				(font
					(size 0.635 0.4064)
					(thickness 0.1524)
				)
			)
		)
		(fp_text user "21"
			(at 3.227832 -2.2606 0)
			(unlocked yes)
			(layer "F.Fab")
			(effects
				(font
					(size 0.635 0.4064)
					(thickness 0.1524)
				)
			)
		)
		(fp_text user "28"
			(at -2.2098 -3.172968 270)
			(unlocked yes)
			(layer "F.Fab")
			(effects
				(font
					(size 0.635 0.4064)
					(thickness 0.1524)
				)
			)
		)
		(fp_text user "22"
			(at 2.2352 -3.172968 270)
			(unlocked yes)
			(layer "F.Fab")
			(effects
				(font
					(size 0.635 0.4064)
					(thickness 0.1524)
				)
			)
		)
		(pad "1" smd rect
			(at -2.412492 -1.500124)
			(size 0.254 0.7366)
			(layers "F.Cu" "F.Mask" "F.Paste")
			(net "USB2_P0_R_DN")
		)
		(pad "2" smd rect
			(at -2.412492 -0.999998)
			(size 0.254 0.7366)
			(layers "F.Cu" "F.Mask" "F.Paste")
			(net "USB2_P0_R_DP")
		)
		(pad "3" smd rect
			(at -2.412492 -0.499872)
			(size 0.254 0.7366)
			(layers "F.Cu" "F.Mask" "F.Paste")
			(net "USB2_HUB_SWB_DN")
		)
		(pad "4" smd rect
			(at -2.412492 0)
			(size 0.254 0.7366)
			(layers "F.Cu" "F.Mask" "F.Paste")
			(net "USB2_HUB_SWB_DP")
		)
		(pad "5" smd rect
			(at -2.412492 0.499872)
			(size 0.254 0.7366)
			(layers "F.Cu" "F.Mask" "F.Paste")
			(net "P3V3_AUX_USB_HUB")
		)
		(pad "6" smd rect
			(at -2.412492 0.999998)
			(size 0.254 0.7366)
			(layers "F.Cu" "F.Mask" "F.Paste")
			(net "NC_USB_HUB_DM2")
		)
		(pad "7" smd rect
			(at -2.412492 1.500124)
			(size 0.254 0.7366)
			(layers "F.Cu" "F.Mask" "F.Paste")
			(net "NC_USB_HUB_DP2")
		)
		(pad "8" smd rect
			(at -1.500124 2.412492 270)
			(size 0.254 0.7366)
			(layers "F.Cu" "F.Mask" "F.Paste")
			(net "USB_HUB_RREF")
		)
		(pad "9" smd rect
			(at -0.999998 2.412492 270)
			(size 0.254 0.7366)
			(layers "F.Cu" "F.Mask" "F.Paste")
			(net "P3V3_AUX_USB_HUB")
		)
		(pad "10" smd rect
			(at -0.499872 2.412492 270)
			(size 0.254 0.7366)
			(layers "F.Cu" "F.Mask" "F.Paste")
			(net "USB_HUB_XTAL_IN")
		)
		(pad "11" smd rect
			(at 0 2.412492 270)
			(size 0.254 0.7366)
			(layers "F.Cu" "F.Mask" "F.Paste")
			(net "USB_HUB_XTAL_OUT")
		)
		(pad "12" smd rect
			(at 0.499872 2.412492 270)
			(size 0.254 0.7366)
			(layers "F.Cu" "F.Mask" "F.Paste")
			(net "NC_USB_HUB_DM3")
		)
		(pad "13" smd rect
			(at 0.999998 2.412492 270)
			(size 0.254 0.7366)
			(layers "F.Cu" "F.Mask" "F.Paste")
			(net "NC_USB_HUB_DP3")
		)
		(pad "14" smd rect
			(at 1.500124 2.412492 270)
			(size 0.254 0.7366)
			(layers "F.Cu" "F.Mask" "F.Paste")
			(net "P3V3_AUX_USB_HUB")
		)
		(pad "15" smd rect
			(at 2.412492 1.500124)
			(size 0.254 0.7366)
			(layers "F.Cu" "F.Mask" "F.Paste")
			(net "NC_USB_HUB_DM4")
		)
		(pad "16" smd rect
			(at 2.412492 0.999998)
			(size 0.254 0.7366)
			(layers "F.Cu" "F.Mask" "F.Paste")
			(net "NC_USB_HUB_DP4")
		)
		(pad "17" smd rect
			(at 2.412492 0.499872)
			(size 0.254 0.7366)
			(layers "F.Cu" "F.Mask" "F.Paste")
			(net "RST_USB_HUB_R_N")
		)
		(pad "18" smd rect
			(at 2.412492 0)
			(size 0.254 0.7366)
			(layers "F.Cu" "F.Mask" "F.Paste")
			(net "USB_HUB_TEST")
		)
		(pad "19" smd rect
			(at 2.412492 -0.499872)
			(size 0.254 0.7366)
			(layers "F.Cu" "F.Mask" "F.Paste")
			(net "USB_HUB_OVCUR4")
		)
		(pad "20" smd rect
			(at 2.412492 -0.999998)
			(size 0.254 0.7366)
			(layers "F.Cu" "F.Mask" "F.Paste")
			(net "USB_HUB_OVCUR3")
		)
		(pad "21" smd rect
			(at 2.412492 -1.500124)
			(size 0.254 0.7366)
			(layers "F.Cu" "F.Mask" "F.Paste")
			(net "USB_HUB_DVDD")
		)
		(pad "22" smd rect
			(at 1.500124 -2.412492 270)
			(size 0.254 0.7366)
			(layers "F.Cu" "F.Mask" "F.Paste")
			(net "USB_HUB_PSELF")
		)
		(pad "23" smd rect
			(at 0.999998 -2.412492 270)
			(size 0.254 0.7366)
			(layers "F.Cu" "F.Mask" "F.Paste")
			(net "USB_HUB_PGANG")
		)
		(pad "24" smd rect
			(at 0.499872 -2.412492 270)
			(size 0.254 0.7366)
			(layers "F.Cu" "F.Mask" "F.Paste")
			(net "USB_HUB_OVCUR2")
		)
		(pad "25" smd rect
			(at 0 -2.412492 270)
			(size 0.254 0.7366)
			(layers "F.Cu" "F.Mask" "F.Paste")
			(net "USB_HUB_OVCUR1")
		)
		(pad "26" smd rect
			(at -0.499872 -2.412492 270)
			(size 0.254 0.7366)
			(layers "F.Cu" "F.Mask" "F.Paste")
			(net "NC_USB_HUB_SDA")
		)
		(pad "27" smd rect
			(at -0.999998 -2.412492 270)
			(size 0.254 0.7366)
			(layers "F.Cu" "F.Mask" "F.Paste")
			(net "P3V3_AUX_USB_HUB")
		)
		(pad "28" smd rect
			(at -1.500124 -2.412492 270)
			(size 0.254 0.7366)
			(layers "F.Cu" "F.Mask" "F.Paste")
			(net "P3V3_AUX_USB_HUB")
		)
		(pad "TH" smd rect
			(at 0 0 270)
			(size 3.556 3.556)
			(layers "F.Cu" "F.Mask" "F.Paste")
			(net "GND")
		)
		(zone
			(layer "F.Cu")
			(hatch none 0.5)
			(connect_pads
				(clearance 0)
			)
			(min_thickness 0.25)
			(keepout
				(tracks not_allowed)
				(vias allowed)
				(pads allowed)
				(copperpour not_allowed)
				(footprints allowed)
			)
			(placement
				(enabled no)
				(sheetname "")
			)
			(fill
				(thermal_gap 0.5)
				(thermal_bridge_width 0.5)
				(island_removal_mode 0)
			)
			(polygon
				(pts
					(xy 16.046196 -98.196654) (xy 15.893796 -98.196654) (xy 15.893796 -100.965254) (xy 12.236196 -100.965254)
					(xy 12.236196 -97.307654) (xy 15.893796 -97.307654) (xy 15.893796 -98.171254) (xy 16.046196 -98.171254)
					(xy 16.046196 -97.155254) (xy 12.083796 -97.155254) (xy 12.083796 -101.117654) (xy 16.046196 -101.117654)
				)
			)
		)
	)
	(footprint ""
		(layer "F.Cu")
		(at 420.52494 -105.207308)
		(property "Reference" "PU205"
			(at -5.1562 -1.20523 0)
			(unlocked yes)
			(layer "F.SilkS")
			(effects
				(font
					(size 0.7874 0.5842)
					(thickness 0.1524)
				)
			)
		)
		(property "Value" ""
			(at 0 0 0)
			(layer "F.Fab")
			(effects
				(font
					(size 1.27 1.27)
				)
			)
		)
		(duplicate_pad_numbers_are_jumpers no)
		(fp_line
			(start -1.239774 -1.495298)
			(end 1.239774 -1.495298)
			(stroke
				(width 0.1524)
				(type default)
			)
			(layer "F.SilkS")
		)
		(fp_line
			(start -1.239774 1.495298)
			(end -1.239774 -1.495298)
			(stroke
				(width 0.1524)
				(type default)
			)
			(layer "F.SilkS")
		)
		(fp_line
			(start 1.239774 -1.495298)
			(end 1.239774 1.495298)
			(stroke
				(width 0.1524)
				(type default)
			)
			(layer "F.SilkS")
		)
		(fp_line
			(start 1.239774 1.495298)
			(end -1.239774 1.495298)
			(stroke
				(width 0.1524)
				(type default)
			)
			(layer "F.SilkS")
		)
		(fp_poly
			(pts
				(xy -1.887474 -1.720596) (xy -1.528318 -0.643128) (xy -2.60604 -1.002284)
			)
			(stroke
				(width 0)
				(type default)
			)
			(fill yes)
			(layer "F.SilkS")
		)
		(fp_line
			(start -0.8001 -1.050036)
			(end 0.8001 -1.050036)
			(stroke
				(width 0.1)
				(type default)
			)
			(layer "F.Fab")
		)
		(fp_line
			(start -0.8001 1.050036)
			(end -0.8001 -1.050036)
			(stroke
				(width 0.1)
				(type default)
			)
			(layer "F.Fab")
		)
		(fp_line
			(start 0.8001 -1.050036)
			(end 0.8001 1.050036)
			(stroke
				(width 0.1)
				(type default)
			)
			(layer "F.Fab")
		)
		(fp_line
			(start 0.8001 1.050036)
			(end -0.8001 1.050036)
			(stroke
				(width 0.1)
				(type default)
			)
			(layer "F.Fab")
		)
		(fp_poly
			(pts
				(xy -2.458974 -0.508) (xy -2.458974 0.508) (xy -1.442974 0)
			)
			(stroke
				(width 0)
				(type default)
			)
			(fill yes)
			(layer "F.Fab")
		)
		(pad "1_2" smd circle
			(at -0.374904 0 90)
			(size 0 0)
			(layers "F.Cu" "F.Mask" "F.Paste")
			(net "P3V3_AUX")
		)
		(pad "3" smd rect
			(at -0.499872 0.999998)
			(size 0.254 0.7112)
			(layers "F.Cu" "F.Mask" "F.Paste")
			(net "GND")
		)
		(pad "4" smd rect
			(at 0 0.999998)
			(size 0.254 0.7112)
			(layers "F.Cu" "F.Mask" "F.Paste")
			(net "P3V3_OCP_ILIMIT_1")
		)
		(pad "5" smd rect
			(at 0.499872 0.999998)
			(size 0.254 0.7112)
			(layers "F.Cu" "F.Mask" "F.Paste")
			(net "P3V3_OCP_MODE_1")
		)
		(pad "6_7" smd circle
			(at 0.374904 0 270)
			(size 0 0)
			(layers "F.Cu" "F.Mask" "F.Paste")
			(net "P3V3_OCP_SFF_R")
		)
		(pad "8" smd rect
			(at 0.499872 -0.999998)
			(size 0.254 0.7112)
			(layers "F.Cu" "F.Mask" "F.Paste")
			(net "P3V3_OCP_GATE_1")
		)
		(pad "9" smd rect
			(at 0 -0.999998)
			(size 0.254 0.7112)
			(layers "F.Cu" "F.Mask" "F.Paste")
			(net "P3V3_OCP_EN_1_R2")
		)
		(pad "10" smd rect
			(at -0.499872 -0.999998)
			(size 0.254 0.7112)
			(layers "F.Cu" "F.Mask" "F.Paste")
			(net "P3V3_OCP_DVDT_1")
		)
	)
	(footprint ""
		(layer "F.Cu")
		(at 121.784364 -355.69779)
		(property "Reference" "R2583"
			(at 0 0 0)
			(layer "F.SilkS")
			(hide yes)
			(effects
				(font
					(size 1.27 1.27)
				)
			)
		)
		(property "Value" ""
			(at 0 0 0)
			(layer "F.Fab")
			(effects
				(font
					(size 1.27 1.27)
				)
			)
		)
		(duplicate_pad_numbers_are_jumpers no)
		(fp_line
			(start -0.7874 -0.4064)
			(end 0.7874 -0.4064)
			(stroke
				(width 0.1524)
				(type default)
			)
			(layer "F.SilkS")
		)
		(fp_line
			(start -0.7874 0.4064)
			(end -0.7874 -0.4064)
			(stroke
				(width 0.1524)
				(type default)
			)
			(layer "F.SilkS")
		)
		(fp_line
			(start 0.7874 -0.4064)
			(end 0.7874 0.4064)
			(stroke
				(width 0.1524)
				(type default)
			)
			(layer "F.SilkS")
		)
		(fp_line
			(start 0.7874 0.4064)
			(end -0.7874 0.4064)
			(stroke
				(width 0.1524)
				(type default)
			)
			(layer "F.SilkS")
		)
		(fp_line
			(start -0.67945 -0.305054)
			(end -0.12065 -0.305054)
			(stroke
				(width 0.1)
				(type default)
			)
			(layer "F.Fab")
		)
		(fp_line
			(start -0.67945 0.3048)
			(end -0.67945 -0.305054)
			(stroke
				(width 0.1)
				(type default)
			)
			(layer "F.Fab")
		)
		(fp_line
			(start -0.12065 -0.305054)
			(end -0.12065 -0.2794)
			(stroke
				(width 0.1)
				(type default)
			)
			(layer "F.Fab")
		)
		(fp_line
			(start -0.12065 -0.2794)
			(end 0.12065 -0.2794)
			(stroke
				(width 0.1)
				(type default)
			)
			(layer "F.Fab")
		)
		(fp_line
			(start -0.12065 0.2794)
			(end -0.12065 0.3048)
			(stroke
				(width 0.1)
				(type default)
			)
			(layer "F.Fab")
		)
		(fp_line
			(start -0.12065 0.3048)
			(end -0.67945 0.3048)
			(stroke
				(width 0.1)
				(type default)
			)
			(layer "F.Fab")
		)
		(fp_line
			(start 0.120396 0.2794)
			(end -0.12065 0.2794)
			(stroke
				(width 0.1)
				(type default)
			)
			(layer "F.Fab")
		)
		(fp_line
			(start 0.120396 0.3048)
			(end 0.120396 0.2794)
			(stroke
				(width 0.1)
				(type default)
			)
			(layer "F.Fab")
		)
		(fp_line
			(start 0.12065 -0.3048)
			(end 0.67945 -0.3048)
			(stroke
				(width 0.1)
				(type default)
			)
			(layer "F.Fab")
		)
		(fp_line
			(start 0.12065 -0.2794)
			(end 0.12065 -0.3048)
			(stroke
				(width 0.1)
				(type default)
			)
			(layer "F.Fab")
		)
		(fp_line
			(start 0.67945 -0.3048)
			(end 0.67945 0.3048)
			(stroke
				(width 0.1)
				(type default)
			)
			(layer "F.Fab")
		)
		(fp_line
			(start 0.67945 0.3048)
			(end 0.120396 0.3048)
			(stroke
				(width 0.1)
				(type default)
			)
			(layer "F.Fab")
		)
		(pad "1" smd circle
			(at -0.40005 0)
			(size 0 0)
			(layers "F.Cu" "F.Mask" "F.Paste")
			(net "P3V3_AUX")
		)
		(pad "2" smd circle
			(at 0.40005 0)
			(size 0 0)
			(layers "F.Cu" "F.Mask" "F.Paste")
			(net "PWRGD_PVPP_HBM_CPU1_R")
		)
	)
)
